(kicad_pcb
	(version 20260206)
	(generator "pcbnew")
	(generator_version "10.0")
	(general
		(thickness 1.6)
		(legacy_teardrops no)
	)
	(paper "A4")
	(title_block
		(title "03242023_DA0F0TMBIJ0_F0T_Motherboard_J_brd_V01_OCP.brd")
		(comment 1 "Grand Teton / footprints 5439-5444 of 6105")
	)
	(layers
		(0 "F.Cu" signal "TOP")
		(4 "In1.Cu" signal "GND")
		(6 "In2.Cu" signal "IN1")
		(8 "In3.Cu" signal "GND1")
		(10 "In4.Cu" signal "IN2")
		(12 "In5.Cu" signal "GND2")
		(14 "In6.Cu" signal "IN3")
		(16 "In7.Cu" signal "GND3")
		(18 "In8.Cu" signal "VCC")
		(20 "In9.Cu" signal "VCC1")
		(22 "In10.Cu" signal "GND4")
		(24 "In11.Cu" signal "IN4")
		(26 "In12.Cu" signal "GND5")
		(28 "In13.Cu" signal "IN5")
		(30 "In14.Cu" signal "GND6")
		(32 "In15.Cu" signal "IN6")
		(34 "In16.Cu" signal "GND7")
		(2 "B.Cu" signal "BOTTOM")
		(9 "F.Adhes" user "F.Adhesive")
		(11 "B.Adhes" user "B.Adhesive")
		(13 "F.Paste" user "Package Geometry/Pastemask Top")
		(15 "B.Paste" user "Package Geometry/Pastemask Bottom")
		(5 "F.SilkS" user "Ref Des/Silkscreen Top")
		(7 "B.SilkS" user "Ref Des/Silkscreen Bottom")
		(1 "F.Mask" user "Board Geometry/Soldermask Top")
		(3 "B.Mask" user "Board Geometry/Soldermask Bottom")
		(17 "Dwgs.User" user "User.Drawings")
		(19 "Cmts.User" user "User.Comments")
		(21 "Eco1.User" user "User.Eco1")
		(23 "Eco2.User" user "User.Eco2")
		(25 "Edge.Cuts" user "Board Geometry/Outline")
		(27 "Margin" user)
		(31 "F.CrtYd" user "Package Geometry/Place Bound Top")
		(29 "B.CrtYd" user "Package Geometry/Place Bound Bottom")
		(35 "F.Fab" user "Ref Des/Assembly Top")
		(33 "B.Fab" user "Ref Des/Assembly Bottom")
	)
	(footprint ""
		(layer "B.Cu")
		(at 192.795906 -72.804528)
		(property "Reference" "C1827"
			(at 0 0 0)
			(layer "B.SilkS")
			(hide yes)
			(effects
				(font
					(size 1.27 1.27)
				)
				(justify mirror)
			)
		)
		(property "Value" ""
			(at 0 0 0)
			(layer "B.Fab")
			(effects
				(font
					(size 1.27 1.27)
				)
				(justify mirror)
			)
		)
		(duplicate_pad_numbers_are_jumpers no)
		(fp_line
			(start -0.7874 -0.4064)
			(end -0.7874 0.4064)
			(stroke
				(width 0.1524)
				(type default)
			)
			(layer "B.SilkS")
		)
		(fp_line
			(start -0.7874 0.4064)
			(end 0.7874 0.4064)
			(stroke
				(width 0.1524)
				(type default)
			)
			(layer "B.SilkS")
		)
		(fp_line
			(start 0.7874 -0.4064)
			(end -0.7874 -0.4064)
			(stroke
				(width 0.1524)
				(type default)
			)
			(layer "B.SilkS")
		)
		(fp_line
			(start 0.7874 0.4064)
			(end 0.7874 -0.4064)
			(stroke
				(width 0.1524)
				(type default)
			)
			(layer "B.SilkS")
		)
		(fp_line
			(start -0.67945 -0.3048)
			(end -0.67945 0.3048)
			(stroke
				(width 0.1)
				(type default)
			)
			(layer "B.Fab")
		)
		(fp_line
			(start -0.67945 0.3048)
			(end -0.120396 0.3048)
			(stroke
				(width 0.1)
				(type default)
			)
			(layer "B.Fab")
		)
		(fp_line
			(start -0.12065 -0.3048)
			(end -0.67945 -0.3048)
			(stroke
				(width 0.1)
				(type default)
			)
			(layer "B.Fab")
		)
		(fp_line
			(start -0.12065 -0.2794)
			(end -0.12065 -0.3048)
			(stroke
				(width 0.1)
				(type default)
			)
			(layer "B.Fab")
		)
		(fp_line
			(start -0.120396 0.2794)
			(end 0.12065 0.2794)
			(stroke
				(width 0.1)
				(type default)
			)
			(layer "B.Fab")
		)
		(fp_line
			(start -0.120396 0.3048)
			(end -0.120396 0.2794)
			(stroke
				(width 0.1)
				(type default)
			)
			(layer "B.Fab")
		)
		(fp_line
			(start 0.12065 -0.305054)
			(end 0.12065 -0.2794)
			(stroke
				(width 0.1)
				(type default)
			)
			(layer "B.Fab")
		)
		(fp_line
			(start 0.12065 -0.2794)
			(end -0.12065 -0.2794)
			(stroke
				(width 0.1)
				(type default)
			)
			(layer "B.Fab")
		)
		(fp_line
			(start 0.12065 0.2794)
			(end 0.12065 0.3048)
			(stroke
				(width 0.1)
				(type default)
			)
			(layer "B.Fab")
		)
		(fp_line
			(start 0.12065 0.3048)
			(end 0.67945 0.3048)
			(stroke
				(width 0.1)
				(type default)
			)
			(layer "B.Fab")
		)
		(fp_line
			(start 0.67945 -0.305054)
			(end 0.12065 -0.305054)
			(stroke
				(width 0.1)
				(type default)
			)
			(layer "B.Fab")
		)
		(fp_line
			(start 0.67945 0.3048)
			(end 0.67945 -0.305054)
			(stroke
				(width 0.1)
				(type default)
			)
			(layer "B.Fab")
		)
		(pad "1" smd circle
			(at 0.40005 0 180)
			(size 0 0)
			(layers "B.Cu" "B.Mask" "B.Paste")
			(net "P3V3_AUX")
		)
		(pad "2" smd circle
			(at -0.40005 0 180)
			(size 0 0)
			(layers "B.Cu" "B.Mask" "B.Paste")
			(net "GND")
		)
	)
	(footprint ""
		(layer "B.Cu")
		(at 340.879938 -44.364402 -149.993)
		(property "Reference" "R495"
			(at 0 0 30.007)
			(layer "B.SilkS")
			(hide yes)
			(effects
				(font
					(size 1.27 1.27)
				)
				(justify mirror)
			)
		)
		(property "Value" ""
			(at 0 0 30.007)
			(layer "B.Fab")
			(effects
				(font
					(size 1.27 1.27)
				)
				(justify mirror)
			)
		)
		(duplicate_pad_numbers_are_jumpers no)
		(fp_line
			(start 0.787502 0.406396)
			(end 0.787346 -0.406469)
			(stroke
				(width 0.1524)
				(type default)
			)
			(layer "B.SilkS")
		)
		(fp_line
			(start 0.787346 -0.406469)
			(end -0.787502 -0.406396)
			(stroke
				(width 0.1524)
				(type default)
			)
			(layer "B.SilkS")
		)
		(fp_line
			(start -0.787346 0.406469)
			(end 0.787502 0.406396)
			(stroke
				(width 0.1524)
				(type default)
			)
			(layer "B.SilkS")
		)
		(fp_line
			(start -0.787502 -0.406396)
			(end -0.787346 0.406469)
			(stroke
				(width 0.1524)
				(type default)
			)
			(layer "B.SilkS")
		)
		(fp_line
			(start 0.67959 0.304771)
			(end 0.679513 -0.305075)
			(stroke
				(width 0.1)
				(type default)
			)
			(layer "B.Fab")
		)
		(fp_line
			(start 0.679513 -0.305075)
			(end 0.120769 -0.30511)
			(stroke
				(width 0.1)
				(type default)
			)
			(layer "B.Fab")
		)
		(fp_line
			(start 0.120499 0.304828)
			(end 0.67959 0.304771)
			(stroke
				(width 0.1)
				(type default)
			)
			(layer "B.Fab")
		)
		(fp_line
			(start 0.120552 0.279341)
			(end 0.120499 0.304828)
			(stroke
				(width 0.1)
				(type default)
			)
			(layer "B.Fab")
		)
		(fp_line
			(start -0.120295 0.304798)
			(end -0.120368 0.27953)
			(stroke
				(width 0.1)
				(type default)
			)
			(layer "B.Fab")
		)
		(fp_line
			(start -0.120368 0.27953)
			(end 0.120552 0.279341)
			(stroke
				(width 0.1)
				(type default)
			)
			(layer "B.Fab")
		)
		(fp_line
			(start 0.120588 -0.279403)
			(end -0.120552 -0.279341)
			(stroke
				(width 0.1)
				(type default)
			)
			(layer "B.Fab")
		)
		(fp_line
			(start 0.120769 -0.30511)
			(end 0.120588 -0.279403)
			(stroke
				(width 0.1)
				(type default)
			)
			(layer "B.Fab")
		)
		(fp_line
			(start -0.120552 -0.279341)
			(end -0.120499 -0.304828)
			(stroke
				(width 0.1)
				(type default)
			)
			(layer "B.Fab")
		)
		(fp_line
			(start -0.120499 -0.304828)
			(end -0.67959 -0.304771)
			(stroke
				(width 0.1)
				(type default)
			)
			(layer "B.Fab")
		)
		(fp_line
			(start -0.679386 0.304855)
			(end -0.120295 0.304798)
			(stroke
				(width 0.1)
				(type default)
			)
			(layer "B.Fab")
		)
		(fp_line
			(start -0.67959 -0.304771)
			(end -0.679386 0.304855)
			(stroke
				(width 0.1)
				(type default)
			)
			(layer "B.Fab")
		)
		(pad "1" smd circle
			(at 0.40005 0 30.007)
			(size 0 0)
			(layers "B.Cu" "B.Mask" "B.Paste")
			(net "PCH_PCIEUP_RCOMPP")
		)
		(pad "2" smd circle
			(at -0.40005 0 30.007)
			(size 0 0)
			(layers "B.Cu" "B.Mask" "B.Paste")
			(net "PCH_PCIEUP_RCOMPN")
		)
	)
	(footprint ""
		(layer "B.Cu")
		(at 372.41988 -43.144948)
		(property "Reference" "R2508"
			(at 0 0 0)
			(layer "B.SilkS")
			(hide yes)
			(effects
				(font
					(size 1.27 1.27)
				)
				(justify mirror)
			)
		)
		(property "Value" ""
			(at 0 0 0)
			(layer "B.Fab")
			(effects
				(font
					(size 1.27 1.27)
				)
				(justify mirror)
			)
		)
		(duplicate_pad_numbers_are_jumpers no)
		(fp_line
			(start -0.7874 -0.4064)
			(end -0.7874 0.4064)
			(stroke
				(width 0.1524)
				(type default)
			)
			(layer "B.SilkS")
		)
		(fp_line
			(start -0.7874 0.4064)
			(end 0.7874 0.4064)
			(stroke
				(width 0.1524)
				(type default)
			)
			(layer "B.SilkS")
		)
		(fp_line
			(start 0.7874 -0.4064)
			(end -0.7874 -0.4064)
			(stroke
				(width 0.1524)
				(type default)
			)
			(layer "B.SilkS")
		)
		(fp_line
			(start 0.7874 0.4064)
			(end 0.7874 -0.4064)
			(stroke
				(width 0.1524)
				(type default)
			)
			(layer "B.SilkS")
		)
		(fp_line
			(start -0.67945 -0.3048)
			(end -0.67945 0.3048)
			(stroke
				(width 0.1)
				(type default)
			)
			(layer "B.Fab")
		)
		(fp_line
			(start -0.67945 0.3048)
			(end -0.120396 0.3048)
			(stroke
				(width 0.1)
				(type default)
			)
			(layer "B.Fab")
		)
		(fp_line
			(start -0.12065 -0.3048)
			(end -0.67945 -0.3048)
			(stroke
				(width 0.1)
				(type default)
			)
			(layer "B.Fab")
		)
		(fp_line
			(start -0.12065 -0.2794)
			(end -0.12065 -0.3048)
			(stroke
				(width 0.1)
				(type default)
			)
			(layer "B.Fab")
		)
		(fp_line
			(start -0.120396 0.2794)
			(end 0.12065 0.2794)
			(stroke
				(width 0.1)
				(type default)
			)
			(layer "B.Fab")
		)
		(fp_line
			(start -0.120396 0.3048)
			(end -0.120396 0.2794)
			(stroke
				(width 0.1)
				(type default)
			)
			(layer "B.Fab")
		)
		(fp_line
			(start 0.12065 -0.305054)
			(end 0.12065 -0.2794)
			(stroke
				(width 0.1)
				(type default)
			)
			(layer "B.Fab")
		)
		(fp_line
			(start 0.12065 -0.2794)
			(end -0.12065 -0.2794)
			(stroke
				(width 0.1)
				(type default)
			)
			(layer "B.Fab")
		)
		(fp_line
			(start 0.12065 0.2794)
			(end 0.12065 0.3048)
			(stroke
				(width 0.1)
				(type default)
			)
			(layer "B.Fab")
		)
		(fp_line
			(start 0.12065 0.3048)
			(end 0.67945 0.3048)
			(stroke
				(width 0.1)
				(type default)
			)
			(layer "B.Fab")
		)
		(fp_line
			(start 0.67945 -0.305054)
			(end 0.12065 -0.305054)
			(stroke
				(width 0.1)
				(type default)
			)
			(layer "B.Fab")
		)
		(fp_line
			(start 0.67945 0.3048)
			(end 0.67945 -0.305054)
			(stroke
				(width 0.1)
				(type default)
			)
			(layer "B.Fab")
		)
		(pad "1" smd circle
			(at 0.40005 0 180)
			(size 0 0)
			(layers "B.Cu" "B.Mask" "B.Paste")
			(net "P3V3_AUX")
		)
		(pad "2" smd circle
			(at -0.40005 0 180)
			(size 0 0)
			(layers "B.Cu" "B.Mask" "B.Paste")
			(net "FM_M2_SSD0_E7_PEDET")
		)
	)
	(footprint ""
		(layer "B.Cu")
		(at 179.9082 -106.76255 -90)
		(property "Reference" "C1899"
			(at 0 0 90)
			(layer "B.SilkS")
			(hide yes)
			(effects
				(font
					(size 1.27 1.27)
				)
				(justify mirror)
			)
		)
		(property "Value" ""
			(at 0 0 90)
			(layer "B.Fab")
			(effects
				(font
					(size 1.27 1.27)
				)
				(justify mirror)
			)
		)
		(duplicate_pad_numbers_are_jumpers no)
		(fp_line
			(start -0.69215 0.2921)
			(end 0.69215 0.2921)
			(stroke
				(width 0.1524)
				(type default)
			)
			(layer "B.SilkS")
		)
		(fp_line
			(start 0.69215 0.2921)
			(end 0.69215 -0.2921)
			(stroke
				(width 0.1524)
				(type default)
			)
			(layer "B.SilkS")
		)
		(fp_line
			(start -0.69215 -0.2921)
			(end -0.69215 0.2921)
			(stroke
				(width 0.1524)
				(type default)
			)
			(layer "B.SilkS")
		)
		(fp_line
			(start 0.69215 -0.2921)
			(end -0.69215 -0.2921)
			(stroke
				(width 0.1524)
				(type default)
			)
			(layer "B.SilkS")
		)
		(fp_line
			(start -0.51435 0.2794)
			(end 0.51435 0.2794)
			(stroke
				(width 0.1)
				(type default)
			)
			(layer "B.Fab")
		)
		(fp_line
			(start 0.51435 0.2794)
			(end 0.51435 -0.2794)
			(stroke
				(width 0.1)
				(type default)
			)
			(layer "B.Fab")
		)
		(fp_line
			(start -0.51435 -0.2794)
			(end -0.51435 0.2794)
			(stroke
				(width 0.1)
				(type default)
			)
			(layer "B.Fab")
		)
		(fp_line
			(start 0.51435 -0.2794)
			(end -0.51435 -0.2794)
			(stroke
				(width 0.1)
				(type default)
			)
			(layer "B.Fab")
		)
		(pad "1" smd circle
			(at 0.40005 0 90)
			(size 0 0)
			(layers "B.Cu" "B.Mask" "B.Paste")
			(net "P3V3_AUX_FPGA_VCCIO4")
		)
		(pad "2" smd circle
			(at -0.40005 0 90)
			(size 0 0)
			(layers "B.Cu" "B.Mask" "B.Paste")
			(net "GND")
		)
		(zone
			(layer "B.Cu")
			(hatch none 0.5)
			(connect_pads
				(clearance 0)
			)
			(min_thickness 0.25)
			(keepout
				(tracks not_allowed)
				(vias allowed)
				(pads allowed)
				(copperpour not_allowed)
				(footprints allowed)
			)
			(placement
				(enabled no)
				(sheetname "")
			)
			(fill
				(thermal_gap 0.5)
				(thermal_bridge_width 0.5)
				(island_removal_mode 0)
			)
			(polygon
				(pts
					(xy 179.82057 -106.57205) (xy 179.762404 -106.66349) (xy 179.762404 -106.86288) (xy 179.82057 -106.95305)
					(xy 179.99583 -106.95305) (xy 180.05425 -106.86288) (xy 180.05425 -106.66349) (xy 179.996084 -106.57205)
				)
			)
		)
	)
	(footprint ""
		(layer "B.Cu")
		(at 336.494882 -188.393578)
		(property "Reference" "R679"
			(at 0 0 0)
			(layer "B.SilkS")
			(hide yes)
			(effects
				(font
					(size 1.27 1.27)
				)
				(justify mirror)
			)
		)
		(property "Value" ""
			(at 0 0 0)
			(layer "B.Fab")
			(effects
				(font
					(size 1.27 1.27)
				)
				(justify mirror)
			)
		)
		(duplicate_pad_numbers_are_jumpers no)
		(fp_line
			(start -0.7874 -0.4064)
			(end -0.7874 0.4064)
			(stroke
				(width 0.1524)
				(type default)
			)
			(layer "B.SilkS")
		)
		(fp_line
			(start -0.7874 0.4064)
			(end 0.7874 0.4064)
			(stroke
				(width 0.1524)
				(type default)
			)
			(layer "B.SilkS")
		)
		(fp_line
			(start 0.7874 -0.4064)
			(end -0.7874 -0.4064)
			(stroke
				(width 0.1524)
				(type default)
			)
			(layer "B.SilkS")
		)
		(fp_line
			(start 0.7874 0.4064)
			(end 0.7874 -0.4064)
			(stroke
				(width 0.1524)
				(type default)
			)
			(layer "B.SilkS")
		)
		(fp_line
			(start -0.67945 -0.3048)
			(end -0.67945 0.3048)
			(stroke
				(width 0.1)
				(type default)
			)
			(layer "B.Fab")
		)
		(fp_line
			(start -0.67945 0.3048)
			(end -0.120396 0.3048)
			(stroke
				(width 0.1)
				(type default)
			)
			(layer "B.Fab")
		)
		(fp_line
			(start -0.12065 -0.3048)
			(end -0.67945 -0.3048)
			(stroke
				(width 0.1)
				(type default)
			)
			(layer "B.Fab")
		)
		(fp_line
			(start -0.12065 -0.2794)
			(end -0.12065 -0.3048)
			(stroke
				(width 0.1)
				(type default)
			)
			(layer "B.Fab")
		)
		(fp_line
			(start -0.120396 0.2794)
			(end 0.12065 0.2794)
			(stroke
				(width 0.1)
				(type default)
			)
			(layer "B.Fab")
		)
		(fp_line
			(start -0.120396 0.3048)
			(end -0.120396 0.2794)
			(stroke
				(width 0.1)
				(type default)
			)
			(layer "B.Fab")
		)
		(fp_line
			(start 0.12065 -0.305054)
			(end 0.12065 -0.2794)
			(stroke
				(width 0.1)
				(type default)
			)
			(layer "B.Fab")
		)
		(fp_line
			(start 0.12065 -0.2794)
			(end -0.12065 -0.2794)
			(stroke
				(width 0.1)
				(type default)
			)
			(layer "B.Fab")
		)
		(fp_line
			(start 0.12065 0.2794)
			(end 0.12065 0.3048)
			(stroke
				(width 0.1)
				(type default)
			)
			(layer "B.Fab")
		)
		(fp_line
			(start 0.12065 0.3048)
			(end 0.67945 0.3048)
			(stroke
				(width 0.1)
				(type default)
			)
			(layer "B.Fab")
		)
		(fp_line
			(start 0.67945 -0.305054)
			(end 0.12065 -0.305054)
			(stroke
				(width 0.1)
				(type default)
			)
			(layer "B.Fab")
		)
		(fp_line
			(start 0.67945 0.3048)
			(end 0.67945 -0.305054)
			(stroke
				(width 0.1)
				(type default)
			)
			(layer "B.Fab")
		)
		(pad "1" smd circle
			(at 0.40005 0 180)
			(size 0 0)
			(layers "B.Cu" "B.Mask" "B.Paste")
			(net "PVNN_TERM_CPU0")
		)
		(pad "2" smd circle
			(at -0.40005 0 180)
			(size 0 0)
			(layers "B.Cu" "B.Mask" "B.Paste")
			(net "I3C_SPD_DDRABCD_CPU0_SCL")
		)
	)
	(footprint ""
		(layer "B.Cu")
		(at 160.83788 -122.646948)
		(property "Reference" "R1412"
			(at 0 0 0)
			(layer "B.SilkS")
			(hide yes)
			(effects
				(font
					(size 1.27 1.27)
				)
				(justify mirror)
			)
		)
		(property "Value" ""
			(at 0 0 0)
			(layer "B.Fab")
			(effects
				(font
					(size 1.27 1.27)
				)
				(justify mirror)
			)
		)
		(duplicate_pad_numbers_are_jumpers no)
		(fp_line
			(start -0.7874 -0.4064)
			(end -0.7874 0.4064)
			(stroke
				(width 0.1524)
				(type default)
			)
			(layer "B.SilkS")
		)
		(fp_line
			(start -0.7874 0.4064)
			(end 0.7874 0.4064)
			(stroke
				(width 0.1524)
				(type default)
			)
			(layer "B.SilkS")
		)
		(fp_line
			(start 0.7874 -0.4064)
			(end -0.7874 -0.4064)
			(stroke
				(width 0.1524)
				(type default)
			)
			(layer "B.SilkS")
		)
		(fp_line
			(start 0.7874 0.4064)
			(end 0.7874 -0.4064)
			(stroke
				(width 0.1524)
				(type default)
			)
			(layer "B.SilkS")
		)
		(fp_line
			(start -0.67945 -0.3048)
			(end -0.67945 0.3048)
			(stroke
				(width 0.1)
				(type default)
			)
			(layer "B.Fab")
		)
		(fp_line
			(start -0.67945 0.3048)
			(end -0.120396 0.3048)
			(stroke
				(width 0.1)
				(type default)
			)
			(layer "B.Fab")
		)
		(fp_line
			(start -0.12065 -0.3048)
			(end -0.67945 -0.3048)
			(stroke
				(width 0.1)
				(type default)
			)
			(layer "B.Fab")
		)
		(fp_line
			(start -0.12065 -0.2794)
			(end -0.12065 -0.3048)
			(stroke
				(width 0.1)
				(type default)
			)
			(layer "B.Fab")
		)
		(fp_line
			(start -0.120396 0.2794)
			(end 0.12065 0.2794)
			(stroke
				(width 0.1)
				(type default)
			)
			(layer "B.Fab")
		)
		(fp_line
			(start -0.120396 0.3048)
			(end -0.120396 0.2794)
			(stroke
				(width 0.1)
				(type default)
			)
			(layer "B.Fab")
		)
		(fp_line
			(start 0.12065 -0.305054)
			(end 0.12065 -0.2794)
			(stroke
				(width 0.1)
				(type default)
			)
			(layer "B.Fab")
		)
		(fp_line
			(start 0.12065 -0.2794)
			(end -0.12065 -0.2794)
			(stroke
				(width 0.1)
				(type default)
			)
			(layer "B.Fab")
		)
		(fp_line
			(start 0.12065 0.2794)
			(end 0.12065 0.3048)
			(stroke
				(width 0.1)
				(type default)
			)
			(layer "B.Fab")
		)
		(fp_line
			(start 0.12065 0.3048)
			(end 0.67945 0.3048)
			(stroke
				(width 0.1)
				(type default)
			)
			(layer "B.Fab")
		)
		(fp_line
			(start 0.67945 -0.305054)
			(end 0.12065 -0.305054)
			(stroke
				(width 0.1)
				(type default)
			)
			(layer "B.Fab")
		)
		(fp_line
			(start 0.67945 0.3048)
			(end 0.67945 -0.305054)
			(stroke
				(width 0.1)
				(type default)
			)
			(layer "B.Fab")
		)
		(pad "1" smd circle
			(at 0.40005 0 180)
			(size 0 0)
			(layers "B.Cu" "B.Mask" "B.Paste")
			(net "FM_PVCCFA_EHV_FIVRA_CPU1_R_EN")
		)
		(pad "2" smd circle
			(at -0.40005 0 180)
			(size 0 0)
			(layers "B.Cu" "B.Mask" "B.Paste")
			(net "GND")
		)
	)
)
